#ISCELL
  mstr_misc dns *
  *
#ISCELL
  mstr_symbols intel_corp_bpage *
  *
#CELL
  mstr_memory m25pe16 *
  page140_i1
#CELL
  mstr_discrete res *
  page140_i10
#CELL
  mstr_discrete res *
  page140_i11
#CELL
  mstr_discrete res *
  page140_i12
#ISCELL
  mstr_symbols p3v3_stby *
  page140_i13
#CELL
  mstr_discrete res *
  page140_i14
#ISCELL
  mstr_symbols gnd *
  page140_i16
#CELL
  mstr_discrete res *
  page140_i17
#CELL
  dev_discrete cap_a *
  page140_i3
#ISCELL
  mstr_symbols gnd *
  page140_i4
#ISCELL
  mstr_standard offpage *
  page140_i5
#ISCELL
  mstr_standard offpage *
  page140_i6
#ISCELL
  mstr_standard offpage *
  page140_i7
#ISCELL
  mstr_standard offpage *
  page140_i8
#ISCELL
  mstr_symbols gnd *
  page140_i9
